# S9S_MB_2U (Grand Teton) — schematic netlist excerpt (pin names and nets, part order shuffled) for the footprints in the layout excerpt that follows; sources: Cadence DE-HDL packaged netlist, KiCad conversion of 03242023_DA0F0TMBIJ0_F0T_Motherboard_J_brd_V01_OCP.brd

J32  SCONN288_ADR50017P087CC  SCONN288_ADR50017-P087CC IO  pkg DDR288S_1-1VXB  page 113
  VIN_BULK0  = P12V_S3_AUX_CPU1_NVDIMM
  RFU0  = TP_CHH_CPU1_DIMM2_FRU_0
  VIN_MGMT  = P3V3_AUX
  HSCL  = I3C_SPD_DDREFGH_CPU1_LVC1_SCL_7
  HSDA  = I3C_SPD_DDREFGH_CPU1_LVC1_SDA
  VSS0  = GND
  DQ0_A  = M_H_CPU1_SA_DQ<0>
  VSS1  = GND
  DQ1_A  = M_H_CPU1_SA_DQ<1>
  VSS2  = GND
  DQS0_A_T  = M_H_CPU1_SA_DQS_DP<0>
  DQS0_A_C  = M_H_CPU1_SA_DQS_DN<0>
  VSS3  = GND
  DQ4_A  = M_H_CPU1_SA_DQ<4>
  VSS4  = GND
  DQ5_A  = M_H_CPU1_SA_DQ<5>
  VSS5  = GND
  DQ8_A  = M_H_CPU1_SA_DQ<8>
  VSS6  = GND
  DQ9_A  = M_H_CPU1_SA_DQ<9>
  VSS7  = GND
  DQS1_A_T  = M_H_CPU1_SA_DQS_DP<1>
  DQS1_A_C  = M_H_CPU1_SA_DQS_DN<1>
  VSS8  = GND
  DQ12_A  = M_H_CPU1_SA_DQ<12>
  VSS9  = GND
  DQ13_A  = M_H_CPU1_SA_DQ<13>
  VSS10  = GND
  DQ16_A  = M_H_CPU1_SA_DQ<16>
  VSS11  = GND
  DQ17_A  = M_H_CPU1_SA_DQ<17>
  VSS12  = GND
  DQS2_A_T  = M_H_CPU1_SA_DQS_DP<2>
  DQS2_A_C  = M_H_CPU1_SA_DQS_DN<2>
  VSS13  = GND
  DQ20_A  = M_H_CPU1_SA_DQ<20>
  VSS14  = GND
  DQ21_A  = M_H_CPU1_SA_DQ<21>
  VSS15  = GND
  DQ24_A  = M_H_CPU1_SA_DQ<24>
  VSS16  = GND
  DQ25_A  = M_H_CPU1_SA_DQ<25>
  VSS17  = GND
  DQS3_A_T  = M_H_CPU1_SA_DQS_DP<3>
  DQS3_A_C  = M_H_CPU1_SA_DQS_DN<3>
  VSS18  = GND
  DQ28_A  = M_H_CPU1_SA_DQ<28>
  VSS19  = GND
  DQ29_A  = M_H_CPU1_SA_DQ<29>
  VSS20  = GND
  CB0_A  = M_H_CPU1_SA_CB<0>
  VSS21  = GND
  CB1_A  = M_H_CPU1_SA_CB<1>
  VSS22  = GND
  DQS4_A_T  = M_H_CPU1_SA_DQS_DP<4>
  DQS4_A_C  = M_H_CPU1_SA_DQS_DN<4>
  VSS23  = GND
  CB4_A  = M_H_CPU1_SA_CB<4>
  VSS24  = GND
  CB5_A  = M_H_CPU1_SA_CB<5>
  VSS25  = GND
  ALERT_N  = M_H_CPU1_ALERT_N
  VSS26  = GND
  CS0_A_N  = M_H_CPU1_SA_CS_N<2>
  VSS27  = GND
  CA0_A  = M_H_CPU1_SA_CA<0>
  VSS28  = GND
  CA2_A  = M_H_CPU1_SA_CA<2>
  VSS29  = GND
  CA4_A  = M_H_CPU1_SA_CA<4>
  VSS30  = GND
  CA6_A  = M_H_CPU1_SA_CA<6>
  VSS31  = GND
  PAR_A  = M_H_CPU1_SA_PAR
  VSS32  = GND
  CA0_B  = M_H_CPU1_SB_CA<0>
  VSS33  = GND
  CA2_B  = M_H_CPU1_SB_CA<2>
  VSS34  = GND
  CA4_B  = M_H_CPU1_SB_CA<4>
  VSS35  = GND
  CA6_B  = M_H_CPU1_SB_CA<6>
  VSS36  = GND
  CS0_B_N  = M_H_CPU1_SB_CS_N<2>
  VSS37  = GND
  \lbd||rsp_a_n\  = M_H_CPU1_SA_RSP<1>
  \lbs||rsp_b_n\  = M_H_CPU1_SB_RSP<1>
  VSS38  = GND
  CB4_B  = M_H_CPU1_SB_CB<4>
  VSS39  = GND
  CB5_B  = M_H_CPU1_SB_CB<5>
  VSS40  = GND
  \dqs9_b_t||tdqs9_b_t||dbi4_b_n\  = M_H_CPU1_SB_DQS_DP<9>
  \dqs9_b_c||tdqs9_b_c\  = M_H_CPU1_SB_DQS_DN<9>
  VSS41  = GND
  CB0_B  = M_H_CPU1_SB_CB<0>
  VSS42  = GND
  CB1_B  = M_H_CPU1_SB_CB<1>
  VSS43  = GND
  DQ0_B  = M_H_CPU1_SB_DQ<0>
  VSS44  = GND
  DQ1_B  = M_H_CPU1_SB_DQ<1>
  VSS45  = GND
  DQS0_B_T  = M_H_CPU1_SB_DQS_DP<0>
  DQS0_B_C  = M_H_CPU1_SB_DQS_DN<0>
  VSS46  = GND
  DQ4_B  = M_H_CPU1_SB_DQ<4>
  VSS47  = GND
  DQ5_B  = M_H_CPU1_SB_DQ<5>
  VSS48  = GND
  DQ8_B  = M_H_CPU1_SB_DQ<8>
  VSS49  = GND
  DQ9_B  = M_H_CPU1_SB_DQ<9>
  VSS50  = GND
  DQS1_B_T  = M_H_CPU1_SB_DQS_DP<1>
  DQS1_B_C  = M_H_CPU1_SB_DQS_DN<1>
  VSS51  = GND
  DQ12_B  = M_H_CPU1_SB_DQ<12>
  VSS52  = GND
  DQ13_B  = M_H_CPU1_SB_DQ<13>
  VSS53  = GND
  DQ16_B  = M_H_CPU1_SB_DQ<16>
  VSS54  = GND
  DQ17_B  = M_H_CPU1_SB_DQ<17>
  VSS55  = GND
  DQS2_B_T  = M_H_CPU1_SB_DQS_DP<2>
  DQS2_B_C  = M_H_CPU1_SB_DQS_DN<2>
  VSS56  = GND
  DQ20_B  = M_H_CPU1_SB_DQ<20>
  VSS57  = GND
  DQ21_B  = M_H_CPU1_SB_DQ<21>
  VSS58  = GND
  DQ24_B  = M_H_CPU1_SB_DQ<24>
  VSS59  = GND
  DQ25_B  = M_H_CPU1_SB_DQ<25>
  VSS60  = GND
  DQS3_B_T  = M_H_CPU1_SB_DQS_DP<3>
  DQS3_B_C  = M_H_CPU1_SB_DQS_DN<3>
  VSS61  = GND
  DQ28_B  = M_H_CPU1_SB_DQ<28>
  VSS62  = GND
  DQ29_B  = M_H_CPU1_SB_DQ<29>
  VSS63  = GND
  RFU1  = TP_CHH_CPU1_DIMM2_FRU_1
  VIN_BULK1  = P12V_S3_AUX_CPU1_NVDIMM
  VIN_BULK2  = P12V_S3_AUX_CPU1_NVDIMM
  \pwr_good||fail_n\  = PWRGD_CHH_CPU1_DIMM2
  HSA  = PD_CHH_CPU1_DIMM2_SAA
  RFU2  = TP_CHH_CPU1_DIMM2_FRU_2
  RFU3  = TP_CHH_CPU1_DIMM2_FRU_3
  VSS64  = GND
  DQ2_A  = M_H_CPU1_SA_DQ<2>
  VSS65  = GND
  DQ3_A  = M_H_CPU1_SA_DQ<3>
  VSS66  = GND
  \dqs5_a_c||tdqs5_a_c||dqs5_a_t||tdqs5_a_t\  = M_H_CPU1_SA_DQS_DN<5>
  \dqs5_a_t||tdqs5_a_t\  = M_H_CPU1_SA_DQS_DP<5>
  VSS67  = GND
  DQ6_A  = M_H_CPU1_SA_DQ<6>
  VSS68  = GND
  DQ7_A  = M_H_CPU1_SA_DQ<7>
  VSS69  = GND
  DQ10_A  = M_H_CPU1_SA_DQ<10>
  VSS70  = GND
  DQ11_A  = M_H_CPU1_SA_DQ<11>
  VSS71  = GND
  \dqs6_a_c||tdqs6_a_c||dqs6_a_t||tdqs6_a_t\  = M_H_CPU1_SA_DQS_DN<6>
  \dqs6_a_t||tdqs6_a_t\  = M_H_CPU1_SA_DQS_DP<6>
  VSS72  = GND
  DQ14_A  = M_H_CPU1_SA_DQ<14>
  VSS73  = GND
  DQ15_A  = M_H_CPU1_SA_DQ<15>
  VSS74  = GND
  DQ18_A  = M_H_CPU1_SA_DQ<18>
  VSS75  = GND
  DQ19_A  = M_H_CPU1_SA_DQ<19>
  VSS76  = GND
  \dqs7_a_c||tdqs7_a_c\  = M_H_CPU1_SA_DQS_DN<7>
  \dqs7_a_t||tdqs7_a_t\  = M_H_CPU1_SA_DQS_DP<7>
  VSS77  = GND
  DQ22_A  = M_H_CPU1_SA_DQ<22>
  VSS78  = GND
  DQ23_A  = M_H_CPU1_SA_DQ<23>
  VSS79  = GND
  DQ26_A  = M_H_CPU1_SA_DQ<26>
  VSS80  = GND
  DQ27_A  = M_H_CPU1_SA_DQ<27>
  VSS81  = GND
  \dqs8_a_c||tdqs8_a_c\  = M_H_CPU1_SA_DQS_DN<8>
  \dqs8_a_t||tdqs8_a_t\  = M_H_CPU1_SA_DQS_DP<8>
  VSS82  = GND
  DQ30_A  = M_H_CPU1_SA_DQ<30>
  VSS83  = GND
  DQ31_A  = M_H_CPU1_SA_DQ<31>
  VSS84  = GND
  CB2_A  = M_H_CPU1_SA_CB<2>
  VSS85  = GND
  CB3_A  = M_H_CPU1_SA_CB<3>
  VSS86  = GND
  \dqs9_a_c||tdqs9_a_c\  = M_H_CPU1_SA_DQS_DN<9>
  \dqs9_a_t||tdqs9_a_t\  = M_H_CPU1_SA_DQS_DP<9>
  VSS87  = GND
  CB6_A  = M_H_CPU1_SA_CB<6>
  VSS88  = GND
  CB7_A  = M_H_CPU1_SA_CB<7>
  VSS89  = GND
  RESET_N  = RST_M_GH_CPU1_FPGA_N
  VSS90  = GND
  CS1_A_N  = M_H_CPU1_SA_CS_N<3>
  VSS91  = GND
  CA1_A  = M_H_CPU1_SA_CA<1>
  VSS92  = GND
  CA3_A  = M_H_CPU1_SA_CA<3>
  VSS93  = GND
  CA5_A  = M_H_CPU1_SA_CA<5>
  VSS94  = GND
  CK_T  = M_H_CPU1_CLK_DP<1>
  CK_C  = M_H_CPU1_CLK_DN<1>
  VSS95  = GND
  RFU4  = TP_CHH_CPU1_DIMM2_FRU_4
  CA1_B  = M_H_CPU1_SB_CA<1>
  VSS96  = GND
  CA3_B  = M_H_CPU1_SB_CA<3>
  VSS97  = GND
  CA5_B  = M_H_CPU1_SB_CA<5>
  VSS98  = GND
  PAR_B  = M_H_CPU1_SB_PAR
  VSS99  = GND
  CS1_B_N  = M_H_CPU1_SB_CS_N<3>
  VSS100  = GND
  RFU5  = TP_CHH_CPU1_DIMM2_FRU_5
  RFU6  = TP_CHH_CPU1_DIMM2_FRU_6
  VSS101  = GND
  CB6_B  = M_H_CPU1_SB_CB<6>
  VSS102  = GND
  CB7_B  = M_H_CPU1_SB_CB<7>
  VSS103  = GND
  DQS4_B_C  = M_H_CPU1_SB_DQS_DN<4>
  DQS4_B_T  = M_H_CPU1_SB_DQS_DP<4>
  VSS104  = GND
  CB2_B  = M_H_CPU1_SB_CB<2>
  VSS105  = GND
  CB3_B  = M_H_CPU1_SB_CB<3>
  VSS106  = GND
  DQ2_B  = M_H_CPU1_SB_DQ<2>
  VSS107  = GND
  DQ3_B  = M_H_CPU1_SB_DQ<3>
  VSS108  = GND
  \dqs5_b_c||tdqs5_b_c\  = M_H_CPU1_SB_DQS_DN<5>
  \dqs5_b_t||tdqs5_b_t\  = M_H_CPU1_SB_DQS_DP<5>
  VSS109  = GND
  DQ6_B  = M_H_CPU1_SB_DQ<6>
  VSS110  = GND
  DQ7_B  = M_H_CPU1_SB_DQ<7>
  VSS111  = GND
  DQ10_B  = M_H_CPU1_SB_DQ<10>
  VSS112  = GND
  DQ11_B  = M_H_CPU1_SB_DQ<11>
  VSS113  = GND
  \dqs6_b_c||tdqs6_b_c\  = M_H_CPU1_SB_DQS_DN<6>
  \dqs6_b_t||tdqs6_b_t\  = M_H_CPU1_SB_DQS_DP<6>
  VSS114  = GND
  DQ14_B  = M_H_CPU1_SB_DQ<14>
  VSS115  = GND
  DQ15_B  = M_H_CPU1_SB_DQ<15>
  VSS116  = GND
  DQ18_B  = M_H_CPU1_SB_DQ<18>
  VSS117  = GND
  DQ19_B  = M_H_CPU1_SB_DQ<19>
  VSS118  = GND
  \dqs7_b_c||tdqs7_b_c\  = M_H_CPU1_SB_DQS_DN<7>
  \dqs7_b_t||tdqs7_b_t\  = M_H_CPU1_SB_DQS_DP<7>
  VSS119  = GND
  DQ22_B  = M_H_CPU1_SB_DQ<22>
  VSS120  = GND
  DQ23_B  = M_H_CPU1_SB_DQ<23>
  VSS121  = GND
  DQ26_B  = M_H_CPU1_SB_DQ<26>
  VSS122  = GND
  DQ27_B  = M_H_CPU1_SB_DQ<27>
  VSS123  = GND
  \dqs8_b_c||tdqs8_b_c\  = M_H_CPU1_SB_DQS_DN<8>
  \dqs8_b_t||tdqs8_b_t\  = M_H_CPU1_SB_DQS_DP<8>
  VSS124  = GND
  DQ30_B  = M_H_CPU1_SB_DQ<30>
  VSS125  = GND
  DQ31_B  = M_H_CPU1_SB_DQ<31>
  VSS126  = GND
  G1  = GND
  G2  = GND
  G3  = GND

(kicad_pcb
	(version 20260206)
	(generator "pcbnew")
	(generator_version "10.0")
	(general
		(thickness 1.6)
		(legacy_teardrops no)
	)
	(paper "A4")
	(title_block
		(title "03242023_DA0F0TMBIJ0_F0T_Motherboard_J_brd_V01_OCP.brd")
		(comment 1 "Grand Teton / footprint 3133 of 6105 (J32), pads 275-291 of 291")
	)
	(layers
		(0 "F.Cu" signal "TOP")
		(4 "In1.Cu" signal "GND")
		(6 "In2.Cu" signal "IN1")
		(8 "In3.Cu" signal "GND1")
		(10 "In4.Cu" signal "IN2")
		(12 "In5.Cu" signal "GND2")
		(14 "In6.Cu" signal "IN3")
		(16 "In7.Cu" signal "GND3")
		(18 "In8.Cu" signal "VCC")
		(20 "In9.Cu" signal "VCC1")
		(22 "In10.Cu" signal "GND4")
		(24 "In11.Cu" signal "IN4")
		(26 "In12.Cu" signal "GND5")
		(28 "In13.Cu" signal "IN5")
		(30 "In14.Cu" signal "GND6")
		(32 "In15.Cu" signal "IN6")
		(34 "In16.Cu" signal "GND7")
		(2 "B.Cu" signal "BOTTOM")
		(9 "F.Adhes" user "F.Adhesive")
		(11 "B.Adhes" user "B.Adhesive")
		(13 "F.Paste" user "Package Geometry/Pastemask Top")
		(15 "B.Paste" user "Package Geometry/Pastemask Bottom")
		(5 "F.SilkS" user "Ref Des/Silkscreen Top")
		(7 "B.SilkS" user "Ref Des/Silkscreen Bottom")
		(1 "F.Mask" user "Board Geometry/Soldermask Top")
		(3 "B.Mask" user "Board Geometry/Soldermask Bottom")
		(17 "Dwgs.User" user "User.Drawings")
		(19 "Cmts.User" user "User.Comments")
		(21 "Eco1.User" user "User.Eco1")
		(23 "Eco2.User" user "User.Eco2")
		(25 "Edge.Cuts" user "Board Geometry/Outline")
		(27 "Margin" user)
		(31 "F.CrtYd" user "Package Geometry/Place Bound Top")
		(29 "B.CrtYd" user "Package Geometry/Place Bound Bottom")
		(35 "F.Fab" user "Ref Des/Assembly Top")
		(33 "B.Fab" user "Ref Des/Assembly Bottom")
	)
	(footprint ""
		(layer "F.Cu")
		(at 206.12608 -258.091686)
		(property "Reference" "J32"
			(at 0.68834 -81.826608 0)
			(unlocked yes)
			(layer "F.SilkS")
			(effects
				(font
					(size 0.7874 0.5842)
					(thickness 0.1524)
				)
				(justify left)
			)
		)
		(property "Value" ""
			(at 0 0 0)
			(layer "F.Fab")
			(effects
				(font
					(size 1.27 1.27)
				)
			)
		)
		(duplicate_pad_numbers_are_jumpers no)
		(pad "275" smd rect
			(at 2.050034 52.274978 270)
			(size 0.519938 1.4986)
			(layers "F.Cu" "F.Mask" "F.Paste")
			(net "GND")
		)
		(pad "276" smd rect
			(at 2.050034 53.125116 270)
			(size 0.519938 1.4986)
			(layers "F.Cu" "F.Mask" "F.Paste")
			(net "M_H_CPU1_SB_DQ<23>")
		)
		(pad "277" smd rect
			(at 2.050034 53.975 270)
			(size 0.519938 1.4986)
			(layers "F.Cu" "F.Mask" "F.Paste")
			(net "GND")
		)
		(pad "278" smd rect
			(at 2.050034 54.824884 270)
			(size 0.519938 1.4986)
			(layers "F.Cu" "F.Mask" "F.Paste")
			(net "M_H_CPU1_SB_DQ<26>")
		)
		(pad "279" smd rect
			(at 2.050034 55.675022 270)
			(size 0.519938 1.4986)
			(layers "F.Cu" "F.Mask" "F.Paste")
			(net "GND")
		)
		(pad "280" smd rect
			(at 2.050034 56.524906 270)
			(size 0.519938 1.4986)
			(layers "F.Cu" "F.Mask" "F.Paste")
			(net "M_H_CPU1_SB_DQ<27>")
		)
		(pad "281" smd rect
			(at 2.050034 57.375044 270)
			(size 0.519938 1.4986)
			(layers "F.Cu" "F.Mask" "F.Paste")
			(net "GND")
		)
		(pad "282" smd rect
			(at 2.050034 58.224928 270)
			(size 0.519938 1.4986)
			(layers "F.Cu" "F.Mask" "F.Paste")
			(net "M_H_CPU1_SB_DQS_DN<8>")
		)
		(pad "283" smd rect
			(at 2.050034 59.075066 270)
			(size 0.519938 1.4986)
			(layers "F.Cu" "F.Mask" "F.Paste")
			(net "M_H_CPU1_SB_DQS_DP<8>")
		)
		(pad "284" smd rect
			(at 2.050034 59.92495 270)
			(size 0.519938 1.4986)
			(layers "F.Cu" "F.Mask" "F.Paste")
			(net "GND")
		)
		(pad "285" smd rect
			(at 2.050034 60.775088 270)
			(size 0.519938 1.4986)
			(layers "F.Cu" "F.Mask" "F.Paste")
			(net "M_H_CPU1_SB_DQ<30>")
		)
		(pad "286" smd rect
			(at 2.050034 61.624972 270)
			(size 0.519938 1.4986)
			(layers "F.Cu" "F.Mask" "F.Paste")
			(net "GND")
		)
		(pad "287" smd rect
			(at 2.050034 62.47511 270)
			(size 0.519938 1.4986)
			(layers "F.Cu" "F.Mask" "F.Paste")
			(net "M_H_CPU1_SB_DQ<31>")
		)
		(pad "288" smd rect
			(at 2.050034 63.324994 270)
			(size 0.519938 1.4986)
			(layers "F.Cu" "F.Mask" "F.Paste")
			(net "GND")
		)
		(pad "G1" thru_hole oval
			(at 0 -68.97497)
			(size 2.8194 1.5748)
			(drill oval 2.4384 1.1938)
			(layers "*.Cu" "*.Mask")
			(remove_unused_layers no)
			(net "GND")
			(clearance 0.127)
			(thermal_gap 0.127)
		)
		(pad "G2" thru_hole oval
			(at 0 3.875024)
			(size 2.8194 1.5748)
			(drill oval 2.4384 1.1938)
			(layers "*.Cu" "*.Mask")
			(remove_unused_layers no)
			(net "GND")
			(clearance 0.127)
			(thermal_gap 0.127)
		)
		(pad "G3" thru_hole oval
			(at 0 68.97497)
			(size 2.8194 1.5748)
			(drill oval 2.4384 1.1938)
			(layers "*.Cu" "*.Mask")
			(remove_unused_layers no)
			(net "GND")
			(clearance 0.127)
			(thermal_gap 0.127)
		)
	)
)
